# SDI-MIPI Bridge — footprint library table
(fp_lib_table
  (lib (name "sdi-mipi-bridge-footprints")(type "KiCad")(uri "${KIPRJMOD}/lib/sdi-mipi-bridge-footprints")(options "")(descr ""))
)
